(kicad_pcb
	(version 20260206)
	(generator "pcbnew")
	(generator_version "10.0")
	(general
		(thickness 1.6)
		(legacy_teardrops no)
	)
	(paper "A4")
	(title_block
		(title "04192023_DAF0TMB3IC0_F0TG_MB_C_brd_V02_OCP.brd")
		(comment 1 "Grand Teton / footprints 1542-1548 of 8354")
	)
	(layers
		(0 "F.Cu" signal "TOP")
		(4 "In1.Cu" signal "GND")
		(6 "In2.Cu" signal "IN1")
		(8 "In3.Cu" signal "GND1")
		(10 "In4.Cu" signal "IN2")
		(12 "In5.Cu" signal "GND2")
		(14 "In6.Cu" signal "IN3")
		(16 "In7.Cu" signal "GND3")
		(18 "In8.Cu" signal "VCC")
		(20 "In9.Cu" signal "VCC1")
		(22 "In10.Cu" signal "GND4")
		(24 "In11.Cu" signal "IN4")
		(26 "In12.Cu" signal "GND5")
		(28 "In13.Cu" signal "IN5")
		(30 "In14.Cu" signal "GND6")
		(32 "In15.Cu" signal "IN6")
		(34 "In16.Cu" signal "GND7")
		(2 "B.Cu" signal "BOTTOM")
		(9 "F.Adhes" user "F.Adhesive")
		(11 "B.Adhes" user "B.Adhesive")
		(13 "F.Paste" user "Package Geometry/Pastemask Top")
		(15 "B.Paste" user "Package Geometry/Pastemask Bottom")
		(5 "F.SilkS" user "Ref Des/Silkscreen Top")
		(7 "B.SilkS" user "Ref Des/Silkscreen Bottom")
		(1 "F.Mask" user "Board Geometry/Soldermask Top")
		(3 "B.Mask" user "Board Geometry/Soldermask Bottom")
		(17 "Dwgs.User" user "User.Drawings")
		(19 "Cmts.User" user "User.Comments")
		(21 "Eco1.User" user "User.Eco1")
		(23 "Eco2.User" user "User.Eco2")
		(25 "Edge.Cuts" user "Board Geometry/Outline")
		(27 "Margin" user)
		(31 "F.CrtYd" user "Package Geometry/Place Bound Top")
		(29 "B.CrtYd" user "Package Geometry/Place Bound Bottom")
		(35 "F.Fab" user "Ref Des/Assembly Top")
		(33 "B.Fab" user "Ref Des/Assembly Bottom")
	)
	(footprint ""
		(layer "F.Cu")
		(at 329.188826 -416.899344 -90)
		(property "Reference" "C6517"
			(at 0 0 270)
			(layer "F.SilkS")
			(hide yes)
			(effects
				(font
					(size 1.27 1.27)
				)
			)
		)
		(property "Value" ""
			(at 0 0 270)
			(layer "F.Fab")
			(effects
				(font
					(size 1.27 1.27)
				)
			)
		)
		(duplicate_pad_numbers_are_jumpers no)
		(fp_line
			(start -0.299974 0.150114)
			(end -0.299974 -0.150114)
			(stroke
				(width 0.1)
				(type default)
			)
			(layer "F.Fab")
		)
		(fp_line
			(start 0.299974 0.150114)
			(end -0.299974 0.150114)
			(stroke
				(width 0.1)
				(type default)
			)
			(layer "F.Fab")
		)
		(fp_line
			(start -0.299974 -0.150114)
			(end 0.299974 -0.150114)
			(stroke
				(width 0.1)
				(type default)
			)
			(layer "F.Fab")
		)
		(fp_line
			(start 0.299974 -0.150114)
			(end 0.299974 0.150114)
			(stroke
				(width 0.1)
				(type default)
			)
			(layer "F.Fab")
		)
		(pad "1" smd rect
			(at -0.2667 0 270)
			(size 0.3048 0.381)
			(layers "F.Cu" "F.Mask" "F.Paste")
			(net "P5E_CPU0_P0_TX_BUF_C_DP<8>")
		)
		(pad "2" smd rect
			(at 0.2667 0 270)
			(size 0.3048 0.381)
			(layers "F.Cu" "F.Mask" "F.Paste")
			(net "P5E_CPU0_P0_TX_BUF_DP<8>")
		)
	)
	(footprint ""
		(layer "F.Cu")
		(at 75.424538 -19.220942)
		(property "Reference" "PC2146"
			(at 0 0 0)
			(layer "F.SilkS")
			(hide yes)
			(effects
				(font
					(size 1.27 1.27)
				)
			)
		)
		(property "Value" ""
			(at 0 0 0)
			(layer "F.Fab")
			(effects
				(font
					(size 1.27 1.27)
				)
			)
		)
		(duplicate_pad_numbers_are_jumpers no)
		(fp_line
			(start -0.7874 -0.4064)
			(end 0.7874 -0.4064)
			(stroke
				(width 0.1524)
				(type default)
			)
			(layer "F.SilkS")
		)
		(fp_line
			(start -0.7874 0.4064)
			(end -0.7874 -0.4064)
			(stroke
				(width 0.1524)
				(type default)
			)
			(layer "F.SilkS")
		)
		(fp_line
			(start 0.7874 -0.4064)
			(end 0.7874 0.4064)
			(stroke
				(width 0.1524)
				(type default)
			)
			(layer "F.SilkS")
		)
		(fp_line
			(start 0.7874 0.4064)
			(end -0.7874 0.4064)
			(stroke
				(width 0.1524)
				(type default)
			)
			(layer "F.SilkS")
		)
		(fp_line
			(start -0.67945 -0.305054)
			(end -0.12065 -0.305054)
			(stroke
				(width 0.1)
				(type default)
			)
			(layer "F.Fab")
		)
		(fp_line
			(start -0.67945 0.3048)
			(end -0.67945 -0.305054)
			(stroke
				(width 0.1)
				(type default)
			)
			(layer "F.Fab")
		)
		(fp_line
			(start -0.12065 -0.305054)
			(end -0.12065 -0.2794)
			(stroke
				(width 0.1)
				(type default)
			)
			(layer "F.Fab")
		)
		(fp_line
			(start -0.12065 -0.2794)
			(end 0.12065 -0.2794)
			(stroke
				(width 0.1)
				(type default)
			)
			(layer "F.Fab")
		)
		(fp_line
			(start -0.12065 0.2794)
			(end -0.12065 0.3048)
			(stroke
				(width 0.1)
				(type default)
			)
			(layer "F.Fab")
		)
		(fp_line
			(start -0.12065 0.3048)
			(end -0.67945 0.3048)
			(stroke
				(width 0.1)
				(type default)
			)
			(layer "F.Fab")
		)
		(fp_line
			(start 0.120396 0.2794)
			(end -0.12065 0.2794)
			(stroke
				(width 0.1)
				(type default)
			)
			(layer "F.Fab")
		)
		(fp_line
			(start 0.120396 0.3048)
			(end 0.120396 0.2794)
			(stroke
				(width 0.1)
				(type default)
			)
			(layer "F.Fab")
		)
		(fp_line
			(start 0.12065 -0.3048)
			(end 0.67945 -0.3048)
			(stroke
				(width 0.1)
				(type default)
			)
			(layer "F.Fab")
		)
		(fp_line
			(start 0.12065 -0.2794)
			(end 0.12065 -0.3048)
			(stroke
				(width 0.1)
				(type default)
			)
			(layer "F.Fab")
		)
		(fp_line
			(start 0.67945 -0.3048)
			(end 0.67945 0.3048)
			(stroke
				(width 0.1)
				(type default)
			)
			(layer "F.Fab")
		)
		(fp_line
			(start 0.67945 0.3048)
			(end 0.120396 0.3048)
			(stroke
				(width 0.1)
				(type default)
			)
			(layer "F.Fab")
		)
		(pad "1" smd circle
			(at -0.40005 0)
			(size 0 0)
			(layers "F.Cu" "F.Mask" "F.Paste")
			(net "GND")
		)
		(pad "2" smd circle
			(at 0.40005 0)
			(size 0 0)
			(layers "F.Cu" "F.Mask" "F.Paste")
			(net "P12V_OCP_REG_2")
		)
	)
	(footprint ""
		(layer "F.Cu")
		(at 171.196 -112.359948 180)
		(property "Reference" "R23"
			(at 0 0 180)
			(layer "F.SilkS")
			(hide yes)
			(effects
				(font
					(size 1.27 1.27)
				)
			)
		)
		(property "Value" ""
			(at 0 0 180)
			(layer "F.Fab")
			(effects
				(font
					(size 1.27 1.27)
				)
			)
		)
		(duplicate_pad_numbers_are_jumpers no)
		(fp_line
			(start 0.7874 0.4064)
			(end -0.7874 0.4064)
			(stroke
				(width 0.1524)
				(type default)
			)
			(layer "F.SilkS")
		)
		(fp_line
			(start 0.7874 -0.4064)
			(end 0.7874 0.4064)
			(stroke
				(width 0.1524)
				(type default)
			)
			(layer "F.SilkS")
		)
		(fp_line
			(start -0.7874 0.4064)
			(end -0.7874 -0.4064)
			(stroke
				(width 0.1524)
				(type default)
			)
			(layer "F.SilkS")
		)
		(fp_line
			(start -0.7874 -0.4064)
			(end 0.7874 -0.4064)
			(stroke
				(width 0.1524)
				(type default)
			)
			(layer "F.SilkS")
		)
		(fp_line
			(start 0.67945 0.3048)
			(end 0.120396 0.3048)
			(stroke
				(width 0.1)
				(type default)
			)
			(layer "F.Fab")
		)
		(fp_line
			(start 0.67945 -0.3048)
			(end 0.67945 0.3048)
			(stroke
				(width 0.1)
				(type default)
			)
			(layer "F.Fab")
		)
		(fp_line
			(start 0.12065 -0.2794)
			(end 0.12065 -0.3048)
			(stroke
				(width 0.1)
				(type default)
			)
			(layer "F.Fab")
		)
		(fp_line
			(start 0.12065 -0.3048)
			(end 0.67945 -0.3048)
			(stroke
				(width 0.1)
				(type default)
			)
			(layer "F.Fab")
		)
		(fp_line
			(start 0.120396 0.3048)
			(end 0.120396 0.2794)
			(stroke
				(width 0.1)
				(type default)
			)
			(layer "F.Fab")
		)
		(fp_line
			(start 0.120396 0.2794)
			(end -0.12065 0.2794)
			(stroke
				(width 0.1)
				(type default)
			)
			(layer "F.Fab")
		)
		(fp_line
			(start -0.12065 0.3048)
			(end -0.67945 0.3048)
			(stroke
				(width 0.1)
				(type default)
			)
			(layer "F.Fab")
		)
		(fp_line
			(start -0.12065 0.2794)
			(end -0.12065 0.3048)
			(stroke
				(width 0.1)
				(type default)
			)
			(layer "F.Fab")
		)
		(fp_line
			(start -0.12065 -0.2794)
			(end 0.12065 -0.2794)
			(stroke
				(width 0.1)
				(type default)
			)
			(layer "F.Fab")
		)
		(fp_line
			(start -0.12065 -0.305054)
			(end -0.12065 -0.2794)
			(stroke
				(width 0.1)
				(type default)
			)
			(layer "F.Fab")
		)
		(fp_line
			(start -0.67945 0.3048)
			(end -0.67945 -0.305054)
			(stroke
				(width 0.1)
				(type default)
			)
			(layer "F.Fab")
		)
		(fp_line
			(start -0.67945 -0.305054)
			(end -0.12065 -0.305054)
			(stroke
				(width 0.1)
				(type default)
			)
			(layer "F.Fab")
		)
		(pad "1" smd circle
			(at -0.40005 0 180)
			(size 0 0)
			(layers "F.Cu" "F.Mask" "F.Paste")
			(net "P3V3_OCP_SFF_EN")
		)
		(pad "2" smd circle
			(at 0.40005 0 180)
			(size 0 0)
			(layers "F.Cu" "F.Mask" "F.Paste")
			(net "P3V3_OCP_SFF_EN_R")
		)
	)
	(footprint ""
		(layer "F.Cu")
		(at 153.88463 -98.355658)
		(property "Reference" "U243"
			(at -3.017774 -1.730502 0)
			(unlocked yes)
			(layer "F.SilkS")
			(effects
				(font
					(size 0.7874 0.5842)
					(thickness 0.1524)
				)
			)
		)
		(property "Value" ""
			(at 0 0 0)
			(layer "F.Fab")
			(effects
				(font
					(size 1.27 1.27)
				)
			)
		)
		(duplicate_pad_numbers_are_jumpers no)
		(fp_line
			(start -1.7272 1.1176)
			(end -1.7272 -1.1176)
			(stroke
				(width 0.1524)
				(type default)
			)
			(layer "F.SilkS")
		)
		(fp_line
			(start -0.254 -1.1176)
			(end -1.7272 -1.1176)
			(stroke
				(width 0.1524)
				(type default)
			)
			(layer "F.SilkS")
		)
		(fp_line
			(start 0 -0.7366)
			(end -0.254 -1.1176)
			(stroke
				(width 0.1524)
				(type default)
			)
			(layer "F.SilkS")
		)
		(fp_line
			(start 0.254 -1.1176)
			(end 0 -0.7366)
			(stroke
				(width 0.1524)
				(type default)
			)
			(layer "F.SilkS")
		)
		(fp_line
			(start 1.7272 -1.1176)
			(end 0.254 -1.1176)
			(stroke
				(width 0.1524)
				(type default)
			)
			(layer "F.SilkS")
		)
		(fp_line
			(start 1.7272 -1.1176)
			(end 1.7272 1.1176)
			(stroke
				(width 0.1524)
				(type default)
			)
			(layer "F.SilkS")
		)
		(fp_line
			(start 1.7272 1.1176)
			(end -1.7272 1.1176)
			(stroke
				(width 0.1524)
				(type default)
			)
			(layer "F.SilkS")
		)
		(fp_poly
			(pts
				(xy -2.7178 -1.030986) (xy -1.9558 -0.649986) (xy -2.7178 -0.268986)
			)
			(stroke
				(width 0)
				(type default)
			)
			(fill yes)
			(layer "F.SilkS")
		)
		(fp_line
			(start -1.5748 -1.1176)
			(end -1.5748 1.1176)
			(stroke
				(width 0.1)
				(type default)
			)
			(layer "F.Fab")
		)
		(fp_line
			(start -1.5748 1.1176)
			(end 1.5748 1.1176)
			(stroke
				(width 0.1)
				(type default)
			)
			(layer "F.Fab")
		)
		(fp_line
			(start 1.5748 -1.1176)
			(end -1.5748 -1.1176)
			(stroke
				(width 0.1)
				(type default)
			)
			(layer "F.Fab")
		)
		(fp_line
			(start 1.5748 1.1176)
			(end 1.5748 -1.1176)
			(stroke
				(width 0.1)
				(type default)
			)
			(layer "F.Fab")
		)
		(fp_poly
			(pts
				(xy -1.9558 -0.649986) (xy -2.7178 -0.268986) (xy -2.7178 -1.030986)
			)
			(stroke
				(width 0)
				(type default)
			)
			(fill yes)
			(layer "F.Fab")
		)
		(pad "1" smd rect
			(at -0.999998 -0.649986 270)
			(size 0.3556 1.1176)
			(layers "F.Cu" "F.Mask" "F.Paste")
			(net "OCP_SFF_NOT_PRSNT_RBT_ARB_IN")
		)
		(pad "2" smd rect
			(at -0.999998 0 270)
			(size 0.3556 1.1176)
			(layers "F.Cu" "F.Mask" "F.Paste")
			(net "GND")
		)
		(pad "3" smd rect
			(at -0.999998 0.649986 270)
			(size 0.3556 1.1176)
			(layers "F.Cu" "F.Mask" "F.Paste")
			(net "OCP_SFF_RBT_ARB_OUT")
		)
		(pad "4" smd rect
			(at 0.999998 0.649986 270)
			(size 0.3556 1.1176)
			(layers "F.Cu" "F.Mask" "F.Paste")
			(net "OCP_SFF_RBT_ARB_IN_MUX2")
		)
		(pad "5" smd rect
			(at 0.999998 0 270)
			(size 0.3556 1.1176)
			(layers "F.Cu" "F.Mask" "F.Paste")
			(net "P3V3_AUX")
		)
		(pad "6" smd rect
			(at 0.999998 -0.649986 270)
			(size 0.3556 1.1176)
			(layers "F.Cu" "F.Mask" "F.Paste")
			(net "OCP_SFF_PRSNT_ALL_R1_N")
		)
	)
	(footprint ""
		(layer "F.Cu")
		(at 14.834108 -128.54559 90)
		(property "Reference" "R4075"
			(at 0 0 90)
			(layer "F.SilkS")
			(hide yes)
			(effects
				(font
					(size 1.27 1.27)
				)
			)
		)
		(property "Value" ""
			(at 0 0 90)
			(layer "F.Fab")
			(effects
				(font
					(size 1.27 1.27)
				)
			)
		)
		(duplicate_pad_numbers_are_jumpers no)
		(fp_line
			(start 0.7874 -0.4064)
			(end 0.7874 0.4064)
			(stroke
				(width 0.1524)
				(type default)
			)
			(layer "F.SilkS")
		)
		(fp_line
			(start -0.7874 -0.4064)
			(end 0.7874 -0.4064)
			(stroke
				(width 0.1524)
				(type default)
			)
			(layer "F.SilkS")
		)
		(fp_line
			(start 0.7874 0.4064)
			(end -0.7874 0.4064)
			(stroke
				(width 0.1524)
				(type default)
			)
			(layer "F.SilkS")
		)
		(fp_line
			(start -0.7874 0.4064)
			(end -0.7874 -0.4064)
			(stroke
				(width 0.1524)
				(type default)
			)
			(layer "F.SilkS")
		)
		(fp_line
			(start -0.12065 -0.305054)
			(end -0.12065 -0.2794)
			(stroke
				(width 0.1)
				(type default)
			)
			(layer "F.Fab")
		)
		(fp_line
			(start -0.67945 -0.305054)
			(end -0.12065 -0.305054)
			(stroke
				(width 0.1)
				(type default)
			)
			(layer "F.Fab")
		)
		(fp_line
			(start 0.67945 -0.3048)
			(end 0.67945 0.3048)
			(stroke
				(width 0.1)
				(type default)
			)
			(layer "F.Fab")
		)
		(fp_line
			(start 0.12065 -0.3048)
			(end 0.67945 -0.3048)
			(stroke
				(width 0.1)
				(type default)
			)
			(layer "F.Fab")
		)
		(fp_line
			(start 0.12065 -0.2794)
			(end 0.12065 -0.3048)
			(stroke
				(width 0.1)
				(type default)
			)
			(layer "F.Fab")
		)
		(fp_line
			(start -0.12065 -0.2794)
			(end 0.12065 -0.2794)
			(stroke
				(width 0.1)
				(type default)
			)
			(layer "F.Fab")
		)
		(fp_line
			(start 0.120396 0.2794)
			(end -0.12065 0.2794)
			(stroke
				(width 0.1)
				(type default)
			)
			(layer "F.Fab")
		)
		(fp_line
			(start -0.12065 0.2794)
			(end -0.12065 0.3048)
			(stroke
				(width 0.1)
				(type default)
			)
			(layer "F.Fab")
		)
		(fp_line
			(start 0.67945 0.3048)
			(end 0.120396 0.3048)
			(stroke
				(width 0.1)
				(type default)
			)
			(layer "F.Fab")
		)
		(fp_line
			(start 0.120396 0.3048)
			(end 0.120396 0.2794)
			(stroke
				(width 0.1)
				(type default)
			)
			(layer "F.Fab")
		)
		(fp_line
			(start -0.12065 0.3048)
			(end -0.67945 0.3048)
			(stroke
				(width 0.1)
				(type default)
			)
			(layer "F.Fab")
		)
		(fp_line
			(start -0.67945 0.3048)
			(end -0.67945 -0.305054)
			(stroke
				(width 0.1)
				(type default)
			)
			(layer "F.Fab")
		)
		(pad "1" smd circle
			(at -0.40005 0 90)
			(size 0 0)
			(layers "F.Cu" "F.Mask" "F.Paste")
			(net "CLK_GEN2_BMC_RC_OE_N")
		)
		(pad "2" smd circle
			(at 0.40005 0 90)
			(size 0 0)
			(layers "F.Cu" "F.Mask" "F.Paste")
			(net "CLK_GEN2_BMC_RC_OE_R3_N")
		)
	)
	(footprint ""
		(layer "F.Cu")
		(at 87.922862 -69.059044 90)
		(property "Reference" "R1170"
			(at 0 0 90)
			(layer "F.SilkS")
			(hide yes)
			(effects
				(font
					(size 1.27 1.27)
				)
			)
		)
		(property "Value" ""
			(at 0 0 90)
			(layer "F.Fab")
			(effects
				(font
					(size 1.27 1.27)
				)
			)
		)
		(duplicate_pad_numbers_are_jumpers no)
		(fp_line
			(start 0.7874 -0.4064)
			(end 0.7874 0.4064)
			(stroke
				(width 0.1524)
				(type default)
			)
			(layer "F.SilkS")
		)
		(fp_line
			(start -0.7874 -0.4064)
			(end 0.7874 -0.4064)
			(stroke
				(width 0.1524)
				(type default)
			)
			(layer "F.SilkS")
		)
		(fp_line
			(start 0.7874 0.4064)
			(end -0.7874 0.4064)
			(stroke
				(width 0.1524)
				(type default)
			)
			(layer "F.SilkS")
		)
		(fp_line
			(start -0.7874 0.4064)
			(end -0.7874 -0.4064)
			(stroke
				(width 0.1524)
				(type default)
			)
			(layer "F.SilkS")
		)
		(fp_line
			(start -0.12065 -0.305054)
			(end -0.12065 -0.2794)
			(stroke
				(width 0.1)
				(type default)
			)
			(layer "F.Fab")
		)
		(fp_line
			(start -0.67945 -0.305054)
			(end -0.12065 -0.305054)
			(stroke
				(width 0.1)
				(type default)
			)
			(layer "F.Fab")
		)
		(fp_line
			(start 0.67945 -0.3048)
			(end 0.67945 0.3048)
			(stroke
				(width 0.1)
				(type default)
			)
			(layer "F.Fab")
		)
		(fp_line
			(start 0.12065 -0.3048)
			(end 0.67945 -0.3048)
			(stroke
				(width 0.1)
				(type default)
			)
			(layer "F.Fab")
		)
		(fp_line
			(start 0.12065 -0.2794)
			(end 0.12065 -0.3048)
			(stroke
				(width 0.1)
				(type default)
			)
			(layer "F.Fab")
		)
		(fp_line
			(start -0.12065 -0.2794)
			(end 0.12065 -0.2794)
			(stroke
				(width 0.1)
				(type default)
			)
			(layer "F.Fab")
		)
		(fp_line
			(start 0.120396 0.2794)
			(end -0.12065 0.2794)
			(stroke
				(width 0.1)
				(type default)
			)
			(layer "F.Fab")
		)
		(fp_line
			(start -0.12065 0.2794)
			(end -0.12065 0.3048)
			(stroke
				(width 0.1)
				(type default)
			)
			(layer "F.Fab")
		)
		(fp_line
			(start 0.67945 0.3048)
			(end 0.120396 0.3048)
			(stroke
				(width 0.1)
				(type default)
			)
			(layer "F.Fab")
		)
		(fp_line
			(start 0.120396 0.3048)
			(end 0.120396 0.2794)
			(stroke
				(width 0.1)
				(type default)
			)
			(layer "F.Fab")
		)
		(fp_line
			(start -0.12065 0.3048)
			(end -0.67945 0.3048)
			(stroke
				(width 0.1)
				(type default)
			)
			(layer "F.Fab")
		)
		(fp_line
			(start -0.67945 0.3048)
			(end -0.67945 -0.305054)
			(stroke
				(width 0.1)
				(type default)
			)
			(layer "F.Fab")
		)
		(pad "1" smd circle
			(at -0.40005 0 90)
			(size 0 0)
			(layers "F.Cu" "F.Mask" "F.Paste")
			(net "OCP_V3_2_P3V3_PLD_PWRGD")
		)
		(pad "2" smd circle
			(at 0.40005 0 90)
			(size 0 0)
			(layers "F.Cu" "F.Mask" "F.Paste")
			(net "OCP_V3_2_P3V3_PLD_R_PWRGD")
		)
	)
	(footprint ""
		(layer "F.Cu")
		(at 229.87 -287.376362 180)
		(property "Reference" "PC6904"
			(at 0 0 180)
			(layer "F.SilkS")
			(hide yes)
			(effects
				(font
					(size 1.27 1.27)
				)
			)
		)
		(property "Value" ""
			(at 0 0 180)
			(layer "F.Fab")
			(effects
				(font
					(size 1.27 1.27)
				)
			)
		)
		(duplicate_pad_numbers_are_jumpers no)
		(fp_line
			(start 1.524 0.762)
			(end -1.524 0.762)
			(stroke
				(width 0.1524)
				(type default)
			)
			(layer "F.SilkS")
		)
		(fp_line
			(start 1.524 -0.762)
			(end 1.524 0.762)
			(stroke
				(width 0.1524)
				(type default)
			)
			(layer "F.SilkS")
		)
		(fp_line
			(start -1.524 0.762)
			(end -1.524 -0.762)
			(stroke
				(width 0.1524)
				(type default)
			)
			(layer "F.SilkS")
		)
		(fp_line
			(start -1.524 -0.762)
			(end 1.524 -0.762)
			(stroke
				(width 0.1524)
				(type default)
			)
			(layer "F.SilkS")
		)
		(fp_line
			(start 1.1049 0.724916)
			(end 1.1049 -0.724916)
			(stroke
				(width 0.1)
				(type default)
			)
			(layer "F.Fab")
		)
		(fp_line
			(start 1.1049 -0.724916)
			(end -1.1049 -0.724916)
			(stroke
				(width 0.1)
				(type default)
			)
			(layer "F.Fab")
		)
		(fp_line
			(start -1.1049 0.724916)
			(end 1.1049 0.724916)
			(stroke
				(width 0.1)
				(type default)
			)
			(layer "F.Fab")
		)
		(fp_line
			(start -1.1049 -0.724916)
			(end -1.1049 0.724916)
			(stroke
				(width 0.1)
				(type default)
			)
			(layer "F.Fab")
		)
		(pad "1" smd rect
			(at -0.889 0)
			(size 1.016 1.27)
			(layers "F.Cu" "F.Mask" "F.Paste")
			(net "SW_P12V_AUX_P1V8_RETIMER_CPU1_FLT")
		)
		(pad "2" smd rect
			(at 0.889 0)
			(size 1.016 1.27)
			(layers "F.Cu" "F.Mask" "F.Paste")
			(net "GND")
		)
	)
)
